(kicad_pcb
	(version 20260206)
	(generator "pcbnew")
	(generator_version "10.0")
	(general
		(thickness 1.6)
		(legacy_teardrops no)
	)
	(paper "A4")
	(title_block
		(title "Wiwynn_Tioga_Pass_MB.brd")
		(comment 1 "Tioga Pass / footprint 2838 of 4770 (J6U2), pads 124-243 of 291")
	)
	(layers
		(0 "F.Cu" signal "TOP")
		(4 "In1.Cu" signal "L2GND")
		(6 "In2.Cu" signal "L3")
		(8 "In3.Cu" signal "L4GND")
		(10 "In4.Cu" signal "L5")
		(12 "In5.Cu" signal "L6GND")
		(14 "In6.Cu" signal "L7VCC")
		(16 "In7.Cu" signal "L8VCC")
		(18 "In8.Cu" signal "L9GND")
		(20 "In9.Cu" signal "L10")
		(22 "In10.Cu" signal "L11GND")
		(24 "In11.Cu" signal "L12")
		(26 "In12.Cu" signal "L13GND")
		(2 "B.Cu" signal "BOTTOM")
		(9 "F.Adhes" user "F.Adhesive")
		(11 "B.Adhes" user "B.Adhesive")
		(13 "F.Paste" user "Package Geometry/Pastemask Top")
		(15 "B.Paste" user "Package Geometry/Pastemask Bottom")
		(5 "F.SilkS" user "Ref Des/Silkscreen Top")
		(7 "B.SilkS" user "Ref Des/Silkscreen Bottom")
		(1 "F.Mask" user "Board Geometry/Soldermask Top")
		(3 "B.Mask" user "Board Geometry/Soldermask Bottom")
		(17 "Dwgs.User" user "User.Drawings")
		(19 "Cmts.User" user "User.Comments")
		(21 "Eco1.User" user "User.Eco1")
		(23 "Eco2.User" user "User.Eco2")
		(25 "Edge.Cuts" user "Board Geometry/Outline")
		(27 "Margin" user)
		(31 "F.CrtYd" user "Package Geometry/Place Bound Top")
		(29 "B.CrtYd" user "Package Geometry/Place Bound Bottom")
		(35 "F.Fab" user "Ref Des/Assembly Top")
		(33 "B.Fab" user "Ref Des/Assembly Bottom")
	)
	(footprint ""
		(layer "B.Cu")
		(at 194.700398 -5.621782 90)
		(property "Reference" "J6U2"
			(at 2.225548 39.48811 0)
			(unlocked yes)
			(layer "B.SilkS")
			(effects
				(font
					(size 0.7874 0.5842)
					(thickness 0.1524)
				)
				(justify left mirror)
			)
		)
		(property "Value" ""
			(at 0 0 90)
			(layer "B.Fab")
			(effects
				(font
					(size 1.27 1.27)
				)
				(justify mirror)
			)
		)
		(duplicate_pad_numbers_are_jumpers no)
		(pad "121" smd rect
			(at 0 107.100116 270)
			(size 1.8034 0.508)
			(layers "B.Cu" "B.Mask" "B.Paste")
			(net "M_C_DQS_DP<15>")
		)
		(pad "122" smd rect
			(at 0 107.95 270)
			(size 1.8034 0.508)
			(layers "B.Cu" "B.Mask" "B.Paste")
			(net "M_C_DQS_DN<15>")
		)
		(pad "123" smd rect
			(at 0 108.799884 270)
			(size 1.8034 0.508)
			(layers "B.Cu" "B.Mask" "B.Paste")
			(net "GND")
		)
		(pad "124" smd rect
			(at 0 109.650022 270)
			(size 1.8034 0.508)
			(layers "B.Cu" "B.Mask" "B.Paste")
			(net "M_C_DQ<54>")
		)
		(pad "125" smd rect
			(at 0 110.499906 270)
			(size 1.8034 0.508)
			(layers "B.Cu" "B.Mask" "B.Paste")
			(net "GND")
		)
		(pad "126" smd rect
			(at 0 111.350044 270)
			(size 1.8034 0.508)
			(layers "B.Cu" "B.Mask" "B.Paste")
			(net "M_C_DQ<50>")
		)
		(pad "127" smd rect
			(at 0 112.199928 270)
			(size 1.8034 0.508)
			(layers "B.Cu" "B.Mask" "B.Paste")
			(net "GND")
		)
		(pad "128" smd rect
			(at 0 113.050066 270)
			(size 1.8034 0.508)
			(layers "B.Cu" "B.Mask" "B.Paste")
			(net "M_C_DQ<60>")
		)
		(pad "129" smd rect
			(at 0 113.89995 270)
			(size 1.8034 0.508)
			(layers "B.Cu" "B.Mask" "B.Paste")
			(net "GND")
		)
		(pad "130" smd rect
			(at 0 114.750088 270)
			(size 1.8034 0.508)
			(layers "B.Cu" "B.Mask" "B.Paste")
			(net "M_C_DQ<56>")
		)
		(pad "131" smd rect
			(at 0 115.599972 270)
			(size 1.8034 0.508)
			(layers "B.Cu" "B.Mask" "B.Paste")
			(net "GND")
		)
		(pad "132" smd rect
			(at 0 116.45011 270)
			(size 1.8034 0.508)
			(layers "B.Cu" "B.Mask" "B.Paste")
			(net "M_C_DQS_DP<16>")
		)
		(pad "133" smd rect
			(at 0 117.299994 270)
			(size 1.8034 0.508)
			(layers "B.Cu" "B.Mask" "B.Paste")
			(net "M_C_DQS_DN<16>")
		)
		(pad "134" smd rect
			(at 0 118.149878 270)
			(size 1.8034 0.508)
			(layers "B.Cu" "B.Mask" "B.Paste")
			(net "GND")
		)
		(pad "135" smd rect
			(at 0 119.000016 270)
			(size 1.8034 0.508)
			(layers "B.Cu" "B.Mask" "B.Paste")
			(net "M_C_DQ<62>")
		)
		(pad "136" smd rect
			(at 0 119.8499 270)
			(size 1.8034 0.508)
			(layers "B.Cu" "B.Mask" "B.Paste")
			(net "GND")
		)
		(pad "137" smd rect
			(at 0 120.700038 270)
			(size 1.8034 0.508)
			(layers "B.Cu" "B.Mask" "B.Paste")
			(net "M_C_DQ<58>")
		)
		(pad "138" smd rect
			(at 0 121.549922 270)
			(size 1.8034 0.508)
			(layers "B.Cu" "B.Mask" "B.Paste")
			(net "GND")
		)
		(pad "139" smd rect
			(at 0 122.40006 270)
			(size 1.8034 0.508)
			(layers "B.Cu" "B.Mask" "B.Paste")
			(net "PVPP_ABC")
		)
		(pad "140" smd rect
			(at 0 123.249944 270)
			(size 1.8034 0.508)
			(layers "B.Cu" "B.Mask" "B.Paste")
			(net "GND")
		)
		(pad "141" smd rect
			(at 0 124.100082 270)
			(size 1.8034 0.508)
			(layers "B.Cu" "B.Mask" "B.Paste")
			(net "SMB_DDR_ABC_VPP_SCL")
		)
		(pad "142" smd rect
			(at 0 124.949966 270)
			(size 1.8034 0.508)
			(layers "B.Cu" "B.Mask" "B.Paste")
			(net "PVPP_ABC")
		)
		(pad "143" smd rect
			(at 0 125.800104 270)
			(size 1.8034 0.508)
			(layers "B.Cu" "B.Mask" "B.Paste")
			(net "PVPP_ABC")
		)
		(pad "144" smd rect
			(at 0 126.649988 270)
			(size 1.8034 0.508)
			(layers "B.Cu" "B.Mask" "B.Paste")
			(net "TP_CH_C_DIMM_C1_RFU_2")
		)
		(pad "145" smd rect
			(at -4.59994 0 270)
			(size 1.8034 0.508)
			(layers "B.Cu" "B.Mask" "B.Paste")
			(net "P12V_NVDIMM_ABC")
		)
		(pad "146" smd rect
			(at -4.59994 0.849884 270)
			(size 1.8034 0.508)
			(layers "B.Cu" "B.Mask" "B.Paste")
			(net "M_C_VREF")
		)
		(pad "147" smd rect
			(at -4.59994 1.700022 270)
			(size 1.8034 0.508)
			(layers "B.Cu" "B.Mask" "B.Paste")
			(net "GND")
		)
		(pad "148" smd rect
			(at -4.59994 2.549906 270)
			(size 1.8034 0.508)
			(layers "B.Cu" "B.Mask" "B.Paste")
			(net "M_C_DQ<5>")
		)
		(pad "149" smd rect
			(at -4.59994 3.400044 270)
			(size 1.8034 0.508)
			(layers "B.Cu" "B.Mask" "B.Paste")
			(net "GND")
		)
		(pad "150" smd rect
			(at -4.59994 4.249928 270)
			(size 1.8034 0.508)
			(layers "B.Cu" "B.Mask" "B.Paste")
			(net "M_C_DQ<1>")
		)
		(pad "151" smd rect
			(at -4.59994 5.100066 270)
			(size 1.8034 0.508)
			(layers "B.Cu" "B.Mask" "B.Paste")
			(net "GND")
		)
		(pad "152" smd rect
			(at -4.59994 5.94995 270)
			(size 1.8034 0.508)
			(layers "B.Cu" "B.Mask" "B.Paste")
			(net "M_C_DQS_DN<0>")
		)
		(pad "153" smd rect
			(at -4.59994 6.800088 270)
			(size 1.8034 0.508)
			(layers "B.Cu" "B.Mask" "B.Paste")
			(net "M_C_DQS_DP<0>")
		)
		(pad "154" smd rect
			(at -4.59994 7.649972 270)
			(size 1.8034 0.508)
			(layers "B.Cu" "B.Mask" "B.Paste")
			(net "GND")
		)
		(pad "155" smd rect
			(at -4.59994 8.50011 270)
			(size 1.8034 0.508)
			(layers "B.Cu" "B.Mask" "B.Paste")
			(net "M_C_DQ<7>")
		)
		(pad "156" smd rect
			(at -4.59994 9.349994 270)
			(size 1.8034 0.508)
			(layers "B.Cu" "B.Mask" "B.Paste")
			(net "GND")
		)
		(pad "157" smd rect
			(at -4.59994 10.199878 270)
			(size 1.8034 0.508)
			(layers "B.Cu" "B.Mask" "B.Paste")
			(net "M_C_DQ<3>")
		)
		(pad "158" smd rect
			(at -4.59994 11.050016 270)
			(size 1.8034 0.508)
			(layers "B.Cu" "B.Mask" "B.Paste")
			(net "GND")
		)
		(pad "159" smd rect
			(at -4.59994 11.8999 270)
			(size 1.8034 0.508)
			(layers "B.Cu" "B.Mask" "B.Paste")
			(net "M_C_DQ<13>")
		)
		(pad "160" smd rect
			(at -4.59994 12.750038 270)
			(size 1.8034 0.508)
			(layers "B.Cu" "B.Mask" "B.Paste")
			(net "GND")
		)
		(pad "161" smd rect
			(at -4.59994 13.599922 270)
			(size 1.8034 0.508)
			(layers "B.Cu" "B.Mask" "B.Paste")
			(net "M_C_DQ<9>")
		)
		(pad "162" smd rect
			(at -4.59994 14.45006 270)
			(size 1.8034 0.508)
			(layers "B.Cu" "B.Mask" "B.Paste")
			(net "GND")
		)
		(pad "163" smd rect
			(at -4.59994 15.299944 270)
			(size 1.8034 0.508)
			(layers "B.Cu" "B.Mask" "B.Paste")
			(net "M_C_DQS_DN<1>")
		)
		(pad "164" smd rect
			(at -4.59994 16.150082 270)
			(size 1.8034 0.508)
			(layers "B.Cu" "B.Mask" "B.Paste")
			(net "M_C_DQS_DP<1>")
		)
		(pad "165" smd rect
			(at -4.59994 16.999966 270)
			(size 1.8034 0.508)
			(layers "B.Cu" "B.Mask" "B.Paste")
			(net "GND")
		)
		(pad "166" smd rect
			(at -4.59994 17.850104 270)
			(size 1.8034 0.508)
			(layers "B.Cu" "B.Mask" "B.Paste")
			(net "M_C_DQ<15>")
		)
		(pad "167" smd rect
			(at -4.59994 18.699988 270)
			(size 1.8034 0.508)
			(layers "B.Cu" "B.Mask" "B.Paste")
			(net "GND")
		)
		(pad "168" smd rect
			(at -4.59994 19.550126 270)
			(size 1.8034 0.508)
			(layers "B.Cu" "B.Mask" "B.Paste")
			(net "M_C_DQ<11>")
		)
		(pad "169" smd rect
			(at -4.59994 20.40001 270)
			(size 1.8034 0.508)
			(layers "B.Cu" "B.Mask" "B.Paste")
			(net "GND")
		)
		(pad "170" smd rect
			(at -4.59994 21.249894 270)
			(size 1.8034 0.508)
			(layers "B.Cu" "B.Mask" "B.Paste")
			(net "M_C_DQ<21>")
		)
		(pad "171" smd rect
			(at -4.59994 22.100032 270)
			(size 1.8034 0.508)
			(layers "B.Cu" "B.Mask" "B.Paste")
			(net "GND")
		)
		(pad "172" smd rect
			(at -4.59994 22.949916 270)
			(size 1.8034 0.508)
			(layers "B.Cu" "B.Mask" "B.Paste")
			(net "M_C_DQ<17>")
		)
		(pad "173" smd rect
			(at -4.59994 23.800054 270)
			(size 1.8034 0.508)
			(layers "B.Cu" "B.Mask" "B.Paste")
			(net "GND")
		)
		(pad "174" smd rect
			(at -4.59994 24.649938 270)
			(size 1.8034 0.508)
			(layers "B.Cu" "B.Mask" "B.Paste")
			(net "M_C_DQS_DN<2>")
		)
		(pad "175" smd rect
			(at -4.59994 25.500076 270)
			(size 1.8034 0.508)
			(layers "B.Cu" "B.Mask" "B.Paste")
			(net "M_C_DQS_DP<2>")
		)
		(pad "176" smd rect
			(at -4.59994 26.34996 270)
			(size 1.8034 0.508)
			(layers "B.Cu" "B.Mask" "B.Paste")
			(net "GND")
		)
		(pad "177" smd rect
			(at -4.59994 27.200098 270)
			(size 1.8034 0.508)
			(layers "B.Cu" "B.Mask" "B.Paste")
			(net "M_C_DQ<23>")
		)
		(pad "178" smd rect
			(at -4.59994 28.049982 270)
			(size 1.8034 0.508)
			(layers "B.Cu" "B.Mask" "B.Paste")
			(net "GND")
		)
		(pad "179" smd rect
			(at -4.59994 28.90012 270)
			(size 1.8034 0.508)
			(layers "B.Cu" "B.Mask" "B.Paste")
			(net "M_C_DQ<19>")
		)
		(pad "180" smd rect
			(at -4.59994 29.750004 270)
			(size 1.8034 0.508)
			(layers "B.Cu" "B.Mask" "B.Paste")
			(net "GND")
		)
		(pad "181" smd rect
			(at -4.59994 30.599888 270)
			(size 1.8034 0.508)
			(layers "B.Cu" "B.Mask" "B.Paste")
			(net "M_C_DQ<29>")
		)
		(pad "182" smd rect
			(at -4.59994 31.450026 270)
			(size 1.8034 0.508)
			(layers "B.Cu" "B.Mask" "B.Paste")
			(net "GND")
		)
		(pad "183" smd rect
			(at -4.59994 32.29991 270)
			(size 1.8034 0.508)
			(layers "B.Cu" "B.Mask" "B.Paste")
			(net "M_C_DQ<25>")
		)
		(pad "184" smd rect
			(at -4.59994 33.150048 270)
			(size 1.8034 0.508)
			(layers "B.Cu" "B.Mask" "B.Paste")
			(net "GND")
		)
		(pad "185" smd rect
			(at -4.59994 33.999932 270)
			(size 1.8034 0.508)
			(layers "B.Cu" "B.Mask" "B.Paste")
			(net "M_C_DQS_DN<3>")
		)
		(pad "186" smd rect
			(at -4.59994 34.85007 270)
			(size 1.8034 0.508)
			(layers "B.Cu" "B.Mask" "B.Paste")
			(net "M_C_DQS_DP<3>")
		)
		(pad "187" smd rect
			(at -4.59994 35.699954 270)
			(size 1.8034 0.508)
			(layers "B.Cu" "B.Mask" "B.Paste")
			(net "GND")
		)
		(pad "188" smd rect
			(at -4.59994 36.550092 270)
			(size 1.8034 0.508)
			(layers "B.Cu" "B.Mask" "B.Paste")
			(net "M_C_DQ<31>")
		)
		(pad "189" smd rect
			(at -4.59994 37.399976 270)
			(size 1.8034 0.508)
			(layers "B.Cu" "B.Mask" "B.Paste")
			(net "GND")
		)
		(pad "190" smd rect
			(at -4.59994 38.250114 270)
			(size 1.8034 0.508)
			(layers "B.Cu" "B.Mask" "B.Paste")
			(net "M_C_DQ<27>")
		)
		(pad "191" smd rect
			(at -4.59994 39.099998 270)
			(size 1.8034 0.508)
			(layers "B.Cu" "B.Mask" "B.Paste")
			(net "GND")
		)
		(pad "192" smd rect
			(at -4.59994 39.949882 270)
			(size 1.8034 0.508)
			(layers "B.Cu" "B.Mask" "B.Paste")
			(net "M_C_ECC<5>")
		)
		(pad "193" smd rect
			(at -4.59994 40.80002 270)
			(size 1.8034 0.508)
			(layers "B.Cu" "B.Mask" "B.Paste")
			(net "GND")
		)
		(pad "194" smd rect
			(at -4.59994 41.649904 270)
			(size 1.8034 0.508)
			(layers "B.Cu" "B.Mask" "B.Paste")
			(net "M_C_ECC<1>")
		)
		(pad "195" smd rect
			(at -4.59994 42.500042 270)
			(size 1.8034 0.508)
			(layers "B.Cu" "B.Mask" "B.Paste")
			(net "GND")
		)
		(pad "196" smd rect
			(at -4.59994 43.349926 270)
			(size 1.8034 0.508)
			(layers "B.Cu" "B.Mask" "B.Paste")
			(net "M_C_DQS_DN<8>")
		)
		(pad "197" smd rect
			(at -4.59994 44.200064 270)
			(size 1.8034 0.508)
			(layers "B.Cu" "B.Mask" "B.Paste")
			(net "M_C_DQS_DP<8>")
		)
		(pad "198" smd rect
			(at -4.59994 45.049948 270)
			(size 1.8034 0.508)
			(layers "B.Cu" "B.Mask" "B.Paste")
			(net "GND")
		)
		(pad "199" smd rect
			(at -4.59994 45.900086 270)
			(size 1.8034 0.508)
			(layers "B.Cu" "B.Mask" "B.Paste")
			(net "M_C_ECC<7>")
		)
		(pad "200" smd rect
			(at -4.59994 46.74997 270)
			(size 1.8034 0.508)
			(layers "B.Cu" "B.Mask" "B.Paste")
			(net "GND")
		)
		(pad "201" smd rect
			(at -4.59994 47.600108 270)
			(size 1.8034 0.508)
			(layers "B.Cu" "B.Mask" "B.Paste")
			(net "M_C_ECC<3>")
		)
		(pad "202" smd rect
			(at -4.59994 48.449992 270)
			(size 1.8034 0.508)
			(layers "B.Cu" "B.Mask" "B.Paste")
			(net "GND")
		)
		(pad "203" smd rect
			(at -4.59994 49.299876 270)
			(size 1.8034 0.508)
			(layers "B.Cu" "B.Mask" "B.Paste")
			(net "M_C_CKE<3>")
		)
		(pad "204" smd rect
			(at -4.59994 50.150014 270)
			(size 1.8034 0.508)
			(layers "B.Cu" "B.Mask" "B.Paste")
			(net "PVDDQ_ABC")
		)
		(pad "205" smd rect
			(at -4.59994 50.999898 270)
			(size 1.8034 0.508)
			(layers "B.Cu" "B.Mask" "B.Paste")
			(net "TP_CH_C_DIMM_C1_RFU_0")
		)
		(pad "206" smd rect
			(at -4.59994 51.850036 270)
			(size 1.8034 0.508)
			(layers "B.Cu" "B.Mask" "B.Paste")
			(net "PVDDQ_ABC")
		)
		(pad "207" smd rect
			(at -4.59994 52.69992 270)
			(size 1.8034 0.508)
			(layers "B.Cu" "B.Mask" "B.Paste")
			(net "M_C_BG<1>")
		)
		(pad "208" smd rect
			(at -4.59994 53.550058 270)
			(size 1.8034 0.508)
			(layers "B.Cu" "B.Mask" "B.Paste")
			(net "M_C_ALERT_N")
		)
		(pad "209" smd rect
			(at -4.59994 54.399942 270)
			(size 1.8034 0.508)
			(layers "B.Cu" "B.Mask" "B.Paste")
			(net "PVDDQ_ABC")
		)
		(pad "210" smd rect
			(at -4.59994 55.25008 270)
			(size 1.8034 0.508)
			(layers "B.Cu" "B.Mask" "B.Paste")
			(net "M_C_MA<11>")
		)
		(pad "211" smd rect
			(at -4.59994 56.099964 270)
			(size 1.8034 0.508)
			(layers "B.Cu" "B.Mask" "B.Paste")
			(net "M_C_MA<7>")
		)
		(pad "212" smd rect
			(at -4.59994 56.950102 270)
			(size 1.8034 0.508)
			(layers "B.Cu" "B.Mask" "B.Paste")
			(net "PVDDQ_ABC")
		)
		(pad "213" smd rect
			(at -4.59994 57.799986 270)
			(size 1.8034 0.508)
			(layers "B.Cu" "B.Mask" "B.Paste")
			(net "M_C_MA<5>")
		)
		(pad "214" smd rect
			(at -4.59994 58.650124 270)
			(size 1.8034 0.508)
			(layers "B.Cu" "B.Mask" "B.Paste")
			(net "M_C_MA<4>")
		)
		(pad "215" smd rect
			(at -4.59994 59.500008 270)
			(size 1.8034 0.508)
			(layers "B.Cu" "B.Mask" "B.Paste")
			(net "PVDDQ_ABC")
		)
		(pad "216" smd rect
			(at -4.59994 60.349892 270)
			(size 1.8034 0.508)
			(layers "B.Cu" "B.Mask" "B.Paste")
			(net "M_C_MA<2>")
		)
		(pad "217" smd rect
			(at -4.59994 61.20003 270)
			(size 1.8034 0.508)
			(layers "B.Cu" "B.Mask" "B.Paste")
			(net "PVDDQ_ABC")
		)
		(pad "218" smd rect
			(at -4.59994 62.049914 270)
			(size 1.8034 0.508)
			(layers "B.Cu" "B.Mask" "B.Paste")
			(net "M_C_CLK_DP<3>")
		)
		(pad "219" smd rect
			(at -4.59994 62.900052 270)
			(size 1.8034 0.508)
			(layers "B.Cu" "B.Mask" "B.Paste")
			(net "M_C_CLK_DN<3>")
		)
		(pad "220" smd rect
			(at -4.59994 63.749936 270)
			(size 1.8034 0.508)
			(layers "B.Cu" "B.Mask" "B.Paste")
			(net "PVDDQ_ABC")
		)
		(pad "221" smd rect
			(at -4.59994 64.600074 270)
			(size 1.8034 0.508)
			(layers "B.Cu" "B.Mask" "B.Paste")
			(net "PVTT_ABC")
		)
		(pad "222" smd rect
			(at -4.59994 70.550024 270)
			(size 1.8034 0.508)
			(layers "B.Cu" "B.Mask" "B.Paste")
			(net "M_C_PAR")
		)
		(pad "223" smd rect
			(at -4.59994 71.399908 270)
			(size 1.8034 0.508)
			(layers "B.Cu" "B.Mask" "B.Paste")
			(net "PVDDQ_ABC")
		)
		(pad "224" smd rect
			(at -4.59994 72.250046 270)
			(size 1.8034 0.508)
			(layers "B.Cu" "B.Mask" "B.Paste")
			(net "M_C_BA<1>")
		)
		(pad "225" smd rect
			(at -4.59994 73.09993 270)
			(size 1.8034 0.508)
			(layers "B.Cu" "B.Mask" "B.Paste")
			(net "M_C_MA<10>")
		)
		(pad "226" smd rect
			(at -4.59994 73.950068 270)
			(size 1.8034 0.508)
			(layers "B.Cu" "B.Mask" "B.Paste")
			(net "PVDDQ_ABC")
		)
		(pad "227" smd rect
			(at -4.59994 74.799952 270)
			(size 1.8034 0.508)
			(layers "B.Cu" "B.Mask" "B.Paste")
			(net "TP_CH_C_DIMM_C1_RFU_1")
		)
		(pad "228" smd rect
			(at -4.59994 75.65009 270)
			(size 1.8034 0.508)
			(layers "B.Cu" "B.Mask" "B.Paste")
			(net "M_C_MA<14>")
		)
		(pad "229" smd rect
			(at -4.59994 76.499974 270)
			(size 1.8034 0.508)
			(layers "B.Cu" "B.Mask" "B.Paste")
			(net "PVDDQ_ABC")
		)
		(pad "230" smd rect
			(at -4.59994 77.350112 270)
			(size 1.8034 0.508)
			(layers "B.Cu" "B.Mask" "B.Paste")
			(net "FM_ADR_COMPLETE_ABC_N")
		)
		(pad "231" smd rect
			(at -4.59994 78.199996 270)
			(size 1.8034 0.508)
			(layers "B.Cu" "B.Mask" "B.Paste")
			(net "PVDDQ_ABC")
		)
		(pad "232" smd rect
			(at -4.59994 79.04988 270)
			(size 1.8034 0.508)
			(layers "B.Cu" "B.Mask" "B.Paste")
			(net "M_C_MA<13>")
		)
		(pad "233" smd rect
			(at -4.59994 79.900018 270)
			(size 1.8034 0.508)
			(layers "B.Cu" "B.Mask" "B.Paste")
			(net "PVDDQ_ABC")
		)
		(pad "234" smd rect
			(at -4.59994 80.749902 270)
			(size 1.8034 0.508)
			(layers "B.Cu" "B.Mask" "B.Paste")
			(net "M_C_MA<17>")
		)
		(pad "235" smd rect
			(at -4.59994 81.60004 270)
			(size 1.8034 0.508)
			(layers "B.Cu" "B.Mask" "B.Paste")
			(net "M_C_C<2>")
		)
		(pad "236" smd rect
			(at -4.59994 82.449924 270)
			(size 1.8034 0.508)
			(layers "B.Cu" "B.Mask" "B.Paste")
			(net "PVDDQ_ABC")
		)
		(pad "237" smd rect
			(at -4.59994 83.300062 270)
			(size 1.8034 0.508)
			(layers "B.Cu" "B.Mask" "B.Paste")
			(net "M_C_CS_N<7>")
		)
		(pad "238" smd rect
			(at -4.59994 84.149946 270)
			(size 1.8034 0.508)
			(layers "B.Cu" "B.Mask" "B.Paste")
			(net "PVPP_ABC")
		)
		(pad "239" smd rect
			(at -4.59994 85.000084 270)
			(size 1.8034 0.508)
			(layers "B.Cu" "B.Mask" "B.Paste")
			(net "GND")
		)
		(pad "240" smd rect
			(at -4.59994 85.849968 270)
			(size 1.8034 0.508)
			(layers "B.Cu" "B.Mask" "B.Paste")
			(net "M_C_DQ<37>")
		)
	)
)
